# BASEBOARD_FAB2 (Tioga Pass) — schematic netlist excerpt (pin names and nets, part order shuffled) for the footprints in the layout excerpt that follows; sources: Cadence DE-HDL packaged netlist, KiCad conversion of Wiwynn_Tioga_Pass_MB.brd

U25W12  TTL3126  74CBTLV3126 IC  pkg QFNLF  page 254
  OE(3)  = BMC_JTAG_SEL_BUF
  A(3)  = BMC_PREQ_N
  B(3)  = BMC_PREQ_BUF_N
  OE(2)  = JTAG_BMC_TCK0
  A(2)  = P1V05_PCH_STBY
  B(2)  = XDP_CPU_TCK0_R
  B(1)  = XDP_PCH_TCK1_R
  A(1)  = P1V05_PCH_STBY
  OE(1)  = JTAG_BMC_TCK1
  B(0)  = XDP_TRST_R_N
  A(0)  = P1V05_PCH_STBY
  OE(0)  = JTAG_BMC_TRST_BUF_N

(kicad_pcb
	(version 20260206)
	(generator "pcbnew")
	(generator_version "10.0")
	(general
		(thickness 1.6)
		(legacy_teardrops no)
	)
	(paper "A4")
	(title_block
		(title "Wiwynn_Tioga_Pass_MB.brd")
		(comment 1 "Tioga Pass / footprints 265-265 of 4770")
	)
	(layers
		(0 "F.Cu" signal "TOP")
		(4 "In1.Cu" signal "L2GND")
		(6 "In2.Cu" signal "L3")
		(8 "In3.Cu" signal "L4GND")
		(10 "In4.Cu" signal "L5")
		(12 "In5.Cu" signal "L6GND")
		(14 "In6.Cu" signal "L7VCC")
		(16 "In7.Cu" signal "L8VCC")
		(18 "In8.Cu" signal "L9GND")
		(20 "In9.Cu" signal "L10")
		(22 "In10.Cu" signal "L11GND")
		(24 "In11.Cu" signal "L12")
		(26 "In12.Cu" signal "L13GND")
		(2 "B.Cu" signal "BOTTOM")
		(9 "F.Adhes" user "F.Adhesive")
		(11 "B.Adhes" user "B.Adhesive")
		(13 "F.Paste" user "Package Geometry/Pastemask Top")
		(15 "B.Paste" user "Package Geometry/Pastemask Bottom")
		(5 "F.SilkS" user "Ref Des/Silkscreen Top")
		(7 "B.SilkS" user "Ref Des/Silkscreen Bottom")
		(1 "F.Mask" user "Board Geometry/Soldermask Top")
		(3 "B.Mask" user "Board Geometry/Soldermask Bottom")
		(17 "Dwgs.User" user "User.Drawings")
		(19 "Cmts.User" user "User.Comments")
		(21 "Eco1.User" user "User.Eco1")
		(23 "Eco2.User" user "User.Eco2")
		(25 "Edge.Cuts" user "Board Geometry/Outline")
		(27 "Margin" user)
		(31 "F.CrtYd" user "Package Geometry/Place Bound Top")
		(29 "B.CrtYd" user "Package Geometry/Place Bound Bottom")
		(35 "F.Fab" user "Ref Des/Assembly Top")
		(33 "B.Fab" user "Ref Des/Assembly Bottom")
	)
	(footprint ""
		(layer "F.Cu")
		(at 439.456322 -151.064468 180)
		(property "Reference" "U25W12"
			(at -1.743964 -3.834638 180)
			(unlocked yes)
			(layer "F.SilkS")
			(effects
				(font
					(size 3.048 1.524)
					(thickness 0.000001)
				)
				(justify left)
			)
		)
		(property "Value" ""
			(at 0 0 180)
			(layer "F.Fab")
			(effects
				(font
					(size 1.27 1.27)
				)
			)
		)
		(duplicate_pad_numbers_are_jumpers no)
		(fp_circle
			(center -2.347468 -1.283462)
			(end -2.474468 -1.283462)
			(stroke
				(width 0.254)
				(type default)
			)
			(fill no)
			(layer "F.SilkS")
		)
		(fp_rect
			(start -0.9144 0.9144)
			(end 0.9144 -0.9144)
			(stroke
				(width 0)
				(type default)
			)
			(fill yes)
			(layer "F.Paste")
		)
		(fp_rect
			(start -1.82499 1.82499)
			(end 1.82499 -1.82499)
			(stroke
				(width 0)
				(type default)
			)
			(fill no)
			(layer "F.CrtYd")
		)
		(fp_line
			(start 1.82499 1.82499)
			(end -1.82499 1.82499)
			(stroke
				(width 0.1)
				(type default)
			)
			(layer "F.Fab")
		)
		(fp_line
			(start 1.82499 -1.82499)
			(end 1.82499 1.82499)
			(stroke
				(width 0.1)
				(type default)
			)
			(layer "F.Fab")
		)
		(fp_line
			(start -1.82499 1.82499)
			(end -1.82499 -1.82499)
			(stroke
				(width 0.1)
				(type default)
			)
			(layer "F.Fab")
		)
		(fp_line
			(start -1.82499 -1.82499)
			(end 1.82499 -1.82499)
			(stroke
				(width 0.1)
				(type default)
			)
			(layer "F.Fab")
		)
		(fp_circle
			(center -1.17856 -2.466086)
			(end -1.30556 -2.466086)
			(stroke
				(width 0.254)
				(type default)
			)
			(fill no)
			(layer "F.Fab")
		)
		(pad "1" smd custom
			(at -0.750062 -1.549908 180)
			(size 0.0762 0.0762)
			(layers "F.Cu" "F.Mask" "F.Paste")
			(net "BMC_JTAG_SEL_BUF")
			(options
				(clearance outline)
				(anchor circle)
			)
			(primitives
				(gr_poly
					(pts
						(xy 0.1524 -0.381)
						(arc
							(start 0.1524 0.2286)
							(mid 0 0.381)
							(end -0.1524 0.2286)
						)
						(xy -0.1524 -0.381)
					)
					(width 0)
					(fill yes)
				)
			)
		)
		(pad "2" smd custom
			(at -1.549908 -0.999998 180)
			(size 0.0762 0.0762)
			(layers "F.Cu" "F.Mask" "F.Paste")
			(net "BMC_PREQ_N")
			(options
				(clearance outline)
				(anchor circle)
			)
			(primitives
				(gr_poly
					(pts
						(xy -0.381 -0.1524)
						(arc
							(start 0.2286 -0.1524)
							(mid 0.381 0)
							(end 0.2286 0.1524)
						)
						(xy -0.381 0.1524)
					)
					(width 0)
					(fill yes)
				)
			)
		)
		(pad "3" smd custom
			(at -1.549908 -0.500126 180)
			(size 0.0762 0.0762)
			(layers "F.Cu" "F.Mask" "F.Paste")
			(net "BMC_PREQ_BUF_N")
			(options
				(clearance outline)
				(anchor circle)
			)
			(primitives
				(gr_poly
					(pts
						(xy -0.381 -0.1524)
						(arc
							(start 0.2286 -0.1524)
							(mid 0.381 0)
							(end 0.2286 0.1524)
						)
						(xy -0.381 0.1524)
					)
					(width 0)
					(fill yes)
				)
			)
		)
		(pad "4" smd custom
			(at -1.549908 0 180)
			(size 0.0762 0.0762)
			(layers "F.Cu" "F.Mask" "F.Paste")
			(net "JTAG_BMC_TCK0")
			(options
				(clearance outline)
				(anchor circle)
			)
			(primitives
				(gr_poly
					(pts
						(xy -0.381 -0.1524)
						(arc
							(start 0.2286 -0.1524)
							(mid 0.381 0)
							(end 0.2286 0.1524)
						)
						(xy -0.381 0.1524)
					)
					(width 0)
					(fill yes)
				)
			)
		)
		(pad "5" smd custom
			(at -1.549908 0.500126 180)
			(size 0.0762 0.0762)
			(layers "F.Cu" "F.Mask" "F.Paste")
			(net "P1V05_PCH_STBY")
			(options
				(clearance outline)
				(anchor circle)
			)
			(primitives
				(gr_poly
					(pts
						(xy -0.381 -0.1524)
						(arc
							(start 0.2286 -0.1524)
							(mid 0.381 0)
							(end 0.2286 0.1524)
						)
						(xy -0.381 0.1524)
					)
					(width 0)
					(fill yes)
				)
			)
		)
		(pad "6" smd custom
			(at -1.549908 0.999998 180)
			(size 0.0762 0.0762)
			(layers "F.Cu" "F.Mask" "F.Paste")
			(net "XDP_CPU_TCK0_R")
			(options
				(clearance outline)
				(anchor circle)
			)
			(primitives
				(gr_poly
					(pts
						(xy -0.381 -0.1524)
						(arc
							(start 0.2286 -0.1524)
							(mid 0.381 0)
							(end 0.2286 0.1524)
						)
						(xy -0.381 0.1524)
					)
					(width 0)
					(fill yes)
				)
			)
		)
		(pad "7" smd custom
			(at -0.750062 1.549908 180)
			(size 0.0762 0.0762)
			(layers "F.Cu" "F.Mask" "F.Paste")
			(net "GND")
			(options
				(clearance outline)
				(anchor circle)
			)
			(primitives
				(gr_poly
					(pts
						(xy -0.1524 0.381)
						(arc
							(start -0.1524 -0.2286)
							(mid 0 -0.381)
							(end 0.1524 -0.2286)
						)
						(xy 0.1524 0.381)
					)
					(width 0)
					(fill yes)
				)
			)
		)
		(pad "8" smd custom
			(at 0.769874 1.549908 180)
			(size 0.0762 0.0762)
			(layers "F.Cu" "F.Mask" "F.Paste")
			(net "XDP_PCH_TCK1_R")
			(options
				(clearance outline)
				(anchor circle)
			)
			(primitives
				(gr_poly
					(pts
						(xy -0.1524 0.381)
						(arc
							(start -0.1524 -0.2286)
							(mid 0 -0.381)
							(end 0.1524 -0.2286)
						)
						(xy 0.1524 0.381)
					)
					(width 0)
					(fill yes)
				)
			)
		)
		(pad "9" smd custom
			(at 1.549908 0.999998 180)
			(size 0.0762 0.0762)
			(layers "F.Cu" "F.Mask" "F.Paste")
			(net "P1V05_PCH_STBY")
			(options
				(clearance outline)
				(anchor circle)
			)
			(primitives
				(gr_poly
					(pts
						(xy 0.381 0.1524)
						(arc
							(start -0.2286 0.1524)
							(mid -0.381 0)
							(end -0.2286 -0.1524)
						)
						(xy 0.381 -0.1524)
					)
					(width 0)
					(fill yes)
				)
			)
		)
		(pad "10" smd custom
			(at 1.549908 0.500126 180)
			(size 0.0762 0.0762)
			(layers "F.Cu" "F.Mask" "F.Paste")
			(net "JTAG_BMC_TCK1")
			(options
				(clearance outline)
				(anchor circle)
			)
			(primitives
				(gr_poly
					(pts
						(xy 0.381 0.1524)
						(arc
							(start -0.2286 0.1524)
							(mid -0.381 0)
							(end -0.2286 -0.1524)
						)
						(xy 0.381 -0.1524)
					)
					(width 0)
					(fill yes)
				)
			)
		)
		(pad "11" smd custom
			(at 1.549908 0 180)
			(size 0.0762 0.0762)
			(layers "F.Cu" "F.Mask" "F.Paste")
			(net "XDP_TRST_R_N")
			(options
				(clearance outline)
				(anchor circle)
			)
			(primitives
				(gr_poly
					(pts
						(xy 0.381 0.1524)
						(arc
							(start -0.2286 0.1524)
							(mid -0.381 0)
							(end -0.2286 -0.1524)
						)
						(xy 0.381 -0.1524)
					)
					(width 0)
					(fill yes)
				)
			)
		)
		(pad "12" smd custom
			(at 1.549908 -0.500126 180)
			(size 0.0762 0.0762)
			(layers "F.Cu" "F.Mask" "F.Paste")
			(net "P1V05_PCH_STBY")
			(options
				(clearance outline)
				(anchor circle)
			)
			(primitives
				(gr_poly
					(pts
						(xy 0.381 0.1524)
						(arc
							(start -0.2286 0.1524)
							(mid -0.381 0)
							(end -0.2286 -0.1524)
						)
						(xy 0.381 -0.1524)
					)
					(width 0)
					(fill yes)
				)
			)
		)
		(pad "13" smd custom
			(at 1.549908 -0.999998 180)
			(size 0.0762 0.0762)
			(layers "F.Cu" "F.Mask" "F.Paste")
			(net "JTAG_BMC_TRST_BUF_N")
			(options
				(clearance outline)
				(anchor circle)
			)
			(primitives
				(gr_poly
					(pts
						(xy 0.381 0.1524)
						(arc
							(start -0.2286 0.1524)
							(mid -0.381 0)
							(end -0.2286 -0.1524)
						)
						(xy 0.381 -0.1524)
					)
					(width 0)
					(fill yes)
				)
			)
		)
		(pad "14" smd custom
			(at 0.750062 -1.549908 180)
			(size 0.0762 0.0762)
			(layers "F.Cu" "F.Mask" "F.Paste")
			(net "P3V3_STBY")
			(options
				(clearance outline)
				(anchor circle)
			)
			(primitives
				(gr_poly
					(pts
						(xy 0.1524 -0.381)
						(arc
							(start 0.1524 0.2286)
							(mid 0 0.381)
							(end -0.1524 0.2286)
						)
						(xy -0.1524 -0.381)
					)
					(width 0)
					(fill yes)
				)
			)
		)
		(pad "15" smd rect
			(at 0 0 180)
			(size 1.8288 1.8288)
			(layers "F.Cu" "F.Mask" "F.Paste")
			(net "GND")
		)
	)
)
